(kicad_pcb
	(version 20260206)
	(generator "pcbnew")
	(generator_version "10.0")
	(general
		(thickness 1.6)
		(legacy_teardrops no)
	)
	(paper "A4")
	(title_block
		(title "04192023_DAF0TMB3IC0_F0TG_MB_C_brd_V02_OCP.brd")
		(comment 1 "Grand Teton / footprints 5753-5757 of 8354")
	)
	(layers
		(0 "F.Cu" signal "TOP")
		(4 "In1.Cu" signal "GND")
		(6 "In2.Cu" signal "IN1")
		(8 "In3.Cu" signal "GND1")
		(10 "In4.Cu" signal "IN2")
		(12 "In5.Cu" signal "GND2")
		(14 "In6.Cu" signal "IN3")
		(16 "In7.Cu" signal "GND3")
		(18 "In8.Cu" signal "VCC")
		(20 "In9.Cu" signal "VCC1")
		(22 "In10.Cu" signal "GND4")
		(24 "In11.Cu" signal "IN4")
		(26 "In12.Cu" signal "GND5")
		(28 "In13.Cu" signal "IN5")
		(30 "In14.Cu" signal "GND6")
		(32 "In15.Cu" signal "IN6")
		(34 "In16.Cu" signal "GND7")
		(2 "B.Cu" signal "BOTTOM")
		(9 "F.Adhes" user "F.Adhesive")
		(11 "B.Adhes" user "B.Adhesive")
		(13 "F.Paste" user "Package Geometry/Pastemask Top")
		(15 "B.Paste" user "Package Geometry/Pastemask Bottom")
		(5 "F.SilkS" user "Ref Des/Silkscreen Top")
		(7 "B.SilkS" user "Ref Des/Silkscreen Bottom")
		(1 "F.Mask" user "Board Geometry/Soldermask Top")
		(3 "B.Mask" user "Board Geometry/Soldermask Bottom")
		(17 "Dwgs.User" user "User.Drawings")
		(19 "Cmts.User" user "User.Comments")
		(21 "Eco1.User" user "User.Eco1")
		(23 "Eco2.User" user "User.Eco2")
		(25 "Edge.Cuts" user "Board Geometry/Outline")
		(27 "Margin" user)
		(31 "F.CrtYd" user "Package Geometry/Place Bound Top")
		(29 "B.CrtYd" user "Package Geometry/Place Bound Bottom")
		(35 "F.Fab" user "Ref Des/Assembly Top")
		(33 "B.Fab" user "Ref Des/Assembly Bottom")
	)
	(footprint ""
		(layer "B.Cu")
		(at 97.902522 -150.698962 -90)
		(property "Reference" "PR436"
			(at 0 0 90)
			(layer "B.SilkS")
			(hide yes)
			(effects
				(font
					(size 1.27 1.27)
				)
				(justify mirror)
			)
		)
		(property "Value" ""
			(at 0 0 90)
			(layer "B.Fab")
			(effects
				(font
					(size 1.27 1.27)
				)
				(justify mirror)
			)
		)
		(duplicate_pad_numbers_are_jumpers no)
		(fp_line
			(start -0.7874 0.4064)
			(end 0.7874 0.4064)
			(stroke
				(width 0.1524)
				(type default)
			)
			(layer "B.SilkS")
		)
		(fp_line
			(start 0.7874 0.4064)
			(end 0.7874 -0.4064)
			(stroke
				(width 0.1524)
				(type default)
			)
			(layer "B.SilkS")
		)
		(fp_line
			(start -0.7874 -0.4064)
			(end -0.7874 0.4064)
			(stroke
				(width 0.1524)
				(type default)
			)
			(layer "B.SilkS")
		)
		(fp_line
			(start 0.7874 -0.4064)
			(end -0.7874 -0.4064)
			(stroke
				(width 0.1524)
				(type default)
			)
			(layer "B.SilkS")
		)
		(fp_line
			(start -0.67945 0.3048)
			(end -0.120396 0.3048)
			(stroke
				(width 0.1)
				(type default)
			)
			(layer "B.Fab")
		)
		(fp_line
			(start -0.120396 0.3048)
			(end -0.120396 0.2794)
			(stroke
				(width 0.1)
				(type default)
			)
			(layer "B.Fab")
		)
		(fp_line
			(start 0.12065 0.3048)
			(end 0.67945 0.3048)
			(stroke
				(width 0.1)
				(type default)
			)
			(layer "B.Fab")
		)
		(fp_line
			(start 0.67945 0.3048)
			(end 0.67945 -0.305054)
			(stroke
				(width 0.1)
				(type default)
			)
			(layer "B.Fab")
		)
		(fp_line
			(start -0.120396 0.2794)
			(end 0.12065 0.2794)
			(stroke
				(width 0.1)
				(type default)
			)
			(layer "B.Fab")
		)
		(fp_line
			(start 0.12065 0.2794)
			(end 0.12065 0.3048)
			(stroke
				(width 0.1)
				(type default)
			)
			(layer "B.Fab")
		)
		(fp_line
			(start -0.12065 -0.2794)
			(end -0.12065 -0.3048)
			(stroke
				(width 0.1)
				(type default)
			)
			(layer "B.Fab")
		)
		(fp_line
			(start 0.12065 -0.2794)
			(end -0.12065 -0.2794)
			(stroke
				(width 0.1)
				(type default)
			)
			(layer "B.Fab")
		)
		(fp_line
			(start -0.67945 -0.3048)
			(end -0.67945 0.3048)
			(stroke
				(width 0.1)
				(type default)
			)
			(layer "B.Fab")
		)
		(fp_line
			(start -0.12065 -0.3048)
			(end -0.67945 -0.3048)
			(stroke
				(width 0.1)
				(type default)
			)
			(layer "B.Fab")
		)
		(fp_line
			(start 0.12065 -0.305054)
			(end 0.12065 -0.2794)
			(stroke
				(width 0.1)
				(type default)
			)
			(layer "B.Fab")
		)
		(fp_line
			(start 0.67945 -0.305054)
			(end 0.12065 -0.305054)
			(stroke
				(width 0.1)
				(type default)
			)
			(layer "B.Fab")
		)
		(pad "1" smd circle
			(at 0.40005 0 90)
			(size 0 0)
			(layers "B.Cu" "B.Mask" "B.Paste")
			(net "NC_PVDDCR_CPU0_P1_IMON8")
		)
		(pad "2" smd circle
			(at -0.40005 0 90)
			(size 0 0)
			(layers "B.Cu" "B.Mask" "B.Paste")
			(net "GND")
		)
	)
	(footprint ""
		(layer "B.Cu")
		(at 394.765276 -177.294794 -90)
		(property "Reference" "PC591_1"
			(at 0 0 90)
			(layer "B.SilkS")
			(hide yes)
			(effects
				(font
					(size 1.27 1.27)
				)
				(justify mirror)
			)
		)
		(property "Value" ""
			(at 0 0 90)
			(layer "B.Fab")
			(effects
				(font
					(size 1.27 1.27)
				)
				(justify mirror)
			)
		)
		(duplicate_pad_numbers_are_jumpers no)
		(fp_line
			(start -1.524 0.762)
			(end 1.524 0.762)
			(stroke
				(width 0.1524)
				(type default)
			)
			(layer "B.SilkS")
		)
		(fp_line
			(start 1.524 0.762)
			(end 1.524 -0.762)
			(stroke
				(width 0.1524)
				(type default)
			)
			(layer "B.SilkS")
		)
		(fp_line
			(start -1.524 -0.762)
			(end -1.524 0.762)
			(stroke
				(width 0.1524)
				(type default)
			)
			(layer "B.SilkS")
		)
		(fp_line
			(start 1.524 -0.762)
			(end -1.524 -0.762)
			(stroke
				(width 0.1524)
				(type default)
			)
			(layer "B.SilkS")
		)
		(fp_line
			(start -1.1049 0.724916)
			(end -1.1049 -0.724916)
			(stroke
				(width 0.1)
				(type default)
			)
			(layer "B.Fab")
		)
		(fp_line
			(start 1.1049 0.724916)
			(end -1.1049 0.724916)
			(stroke
				(width 0.1)
				(type default)
			)
			(layer "B.Fab")
		)
		(fp_line
			(start -1.1049 -0.724916)
			(end 1.1049 -0.724916)
			(stroke
				(width 0.1)
				(type default)
			)
			(layer "B.Fab")
		)
		(fp_line
			(start 1.1049 -0.724916)
			(end 1.1049 0.724916)
			(stroke
				(width 0.1)
				(type default)
			)
			(layer "B.Fab")
		)
		(pad "1" smd rect
			(at 0.889 0 270)
			(size 1.016 1.27)
			(layers "B.Cu" "B.Mask" "B.Paste")
			(net "SW_P12V_AUX_PVDDCR_SOC_P0_FLT")
		)
		(pad "2" smd rect
			(at -0.889 0 270)
			(size 1.016 1.27)
			(layers "B.Cu" "B.Mask" "B.Paste")
			(net "GND")
		)
	)
	(footprint ""
		(layer "B.Cu")
		(at 300.538388 -2.537206)
		(property "Reference" "J86"
			(at 4.532122 1.115568 270)
			(unlocked yes)
			(layer "B.SilkS")
			(effects
				(font
					(size 0.7874 0.5842)
					(thickness 0.1524)
				)
				(justify left mirror)
			)
		)
		(property "Value" ""
			(at 0 0 0)
			(layer "B.Fab")
			(effects
				(font
					(size 1.27 1.27)
				)
				(justify mirror)
			)
		)
		(duplicate_pad_numbers_are_jumpers no)
		(fp_line
			(start -1.2192 -2.06756)
			(end -1.2192 2.06756)
			(stroke
				(width 0.1524)
				(type default)
			)
			(layer "B.SilkS")
		)
		(fp_line
			(start -1.2192 2.06756)
			(end 1.2192 2.06756)
			(stroke
				(width 0.1524)
				(type default)
			)
			(layer "B.SilkS")
		)
		(fp_line
			(start 1.2192 -2.06756)
			(end -1.2192 -2.06756)
			(stroke
				(width 0.1524)
				(type default)
			)
			(layer "B.SilkS")
		)
		(fp_line
			(start 1.2192 2.06756)
			(end 1.2192 -2.06756)
			(stroke
				(width 0.1524)
				(type default)
			)
			(layer "B.SilkS")
		)
		(pad "" np_thru_hole circle
			(at -3.4671 -1.27 270)
			(size 1.0414 1.0414)
			(drill 1.0414)
			(layers "*.Cu" "*.Mask")
			(clearance 0.381)
			(thermal_gap 0.381)
		)
		(pad "" np_thru_hole circle
			(at -3.4671 1.27 270)
			(size 1.0414 1.0414)
			(drill 1.0414)
			(layers "*.Cu" "*.Mask")
			(clearance 0.381)
			(thermal_gap 0.381)
		)
		(pad "" np_thru_hole circle
			(at 2.8829 -1.27 270)
			(size 1.0414 1.0414)
			(drill 1.0414)
			(layers "*.Cu" "*.Mask")
			(clearance 0.381)
			(thermal_gap 0.381)
		)
		(pad "" np_thru_hole circle
			(at 2.8829 1.27 270)
			(size 1.0414 1.0414)
			(drill 1.0414)
			(layers "*.Cu" "*.Mask")
			(clearance 0.381)
			(thermal_gap 0.381)
		)
		(pad "1" smd rect
			(at -0.8255 -0.249936 270)
			(size 0.3048 0.508)
			(layers "B.Cu" "B.Mask" "B.Paste")
			(net "DELTA_L_85_10INCH_IN4_DN")
		)
		(pad "2" smd rect
			(at -0.8255 0.249936 270)
			(size 0.3048 0.508)
			(layers "B.Cu" "B.Mask" "B.Paste")
			(net "DELTA_L_85_10INCH_IN4_DP")
		)
		(pad "3" smd circle
			(at 0 0 180)
			(size 0 0)
			(layers "B.Cu" "B.Mask" "B.Paste")
			(net "DELTA_L_GND_1")
		)
		(zone
			(layers "F.Cu" "B.Cu" "In1.Cu" "In2.Cu" "In3.Cu" "In4.Cu" "In5.Cu" "In6.Cu"
				"In7.Cu" "In8.Cu" "In9.Cu" "In10.Cu" "In11.Cu" "In12.Cu" "In13.Cu" "In14.Cu"
				"In15.Cu" "In16.Cu"
			)
			(hatch none 0.5)
			(connect_pads
				(clearance 0)
			)
			(min_thickness 0.25)
			(keepout
				(tracks not_allowed)
				(vias allowed)
				(pads allowed)
				(copperpour not_allowed)
				(footprints allowed)
			)
			(placement
				(enabled no)
				(sheetname "")
			)
			(fill
				(thermal_gap 0.5)
				(thermal_bridge_width 0.5)
				(island_removal_mode 0)
			)
			(polygon
				(pts
					(arc
						(start 297.998388 -3.807206)
						(mid 296.144188 -3.807206)
						(end 297.998388 -3.807206)
					)
				)
			)
		)
		(zone
			(layers "F.Cu" "B.Cu" "In1.Cu" "In2.Cu" "In3.Cu" "In4.Cu" "In5.Cu" "In6.Cu"
				"In7.Cu" "In8.Cu" "In9.Cu" "In10.Cu" "In11.Cu" "In12.Cu" "In13.Cu" "In14.Cu"
				"In15.Cu" "In16.Cu"
			)
			(hatch none 0.5)
			(connect_pads
				(clearance 0)
			)
			(min_thickness 0.25)
			(keepout
				(tracks not_allowed)
				(vias allowed)
				(pads allowed)
				(copperpour not_allowed)
				(footprints allowed)
			)
			(placement
				(enabled no)
				(sheetname "")
			)
			(fill
				(thermal_gap 0.5)
				(thermal_bridge_width 0.5)
				(island_removal_mode 0)
			)
			(polygon
				(pts
					(arc
						(start 297.998388 -1.267206)
						(mid 296.144188 -1.267206)
						(end 297.998388 -1.267206)
					)
				)
			)
		)
		(zone
			(layers "F.Cu" "B.Cu" "In1.Cu" "In2.Cu" "In3.Cu" "In4.Cu" "In5.Cu" "In6.Cu"
				"In7.Cu" "In8.Cu" "In9.Cu" "In10.Cu" "In11.Cu" "In12.Cu" "In13.Cu" "In14.Cu"
				"In15.Cu" "In16.Cu"
			)
			(hatch none 0.5)
			(connect_pads
				(clearance 0)
			)
			(min_thickness 0.25)
			(keepout
				(tracks not_allowed)
				(vias allowed)
				(pads allowed)
				(copperpour not_allowed)
				(footprints allowed)
			)
			(placement
				(enabled no)
				(sheetname "")
			)
			(fill
				(thermal_gap 0.5)
				(thermal_bridge_width 0.5)
				(island_removal_mode 0)
			)
			(polygon
				(pts
					(arc
						(start 304.348388 -3.807206)
						(mid 302.494188 -3.807206)
						(end 304.348388 -3.807206)
					)
				)
			)
		)
		(zone
			(layers "F.Cu" "B.Cu" "In1.Cu" "In2.Cu" "In3.Cu" "In4.Cu" "In5.Cu" "In6.Cu"
				"In7.Cu" "In8.Cu" "In9.Cu" "In10.Cu" "In11.Cu" "In12.Cu" "In13.Cu" "In14.Cu"
				"In15.Cu" "In16.Cu"
			)
			(hatch none 0.5)
			(connect_pads
				(clearance 0)
			)
			(min_thickness 0.25)
			(keepout
				(tracks not_allowed)
				(vias allowed)
				(pads allowed)
				(copperpour not_allowed)
				(footprints allowed)
			)
			(placement
				(enabled no)
				(sheetname "")
			)
			(fill
				(thermal_gap 0.5)
				(thermal_bridge_width 0.5)
				(island_removal_mode 0)
			)
			(polygon
				(pts
					(arc
						(start 304.348388 -1.267206)
						(mid 302.494188 -1.267206)
						(end 304.348388 -1.267206)
					)
				)
			)
		)
		(zone
			(layer "B.Cu")
			(hatch none 0.5)
			(connect_pads
				(clearance 0)
			)
			(min_thickness 0.25)
			(keepout
				(tracks not_allowed)
				(vias allowed)
				(pads allowed)
				(copperpour not_allowed)
				(footprints allowed)
			)
			(placement
				(enabled no)
				(sheetname "")
			)
			(fill
				(thermal_gap 0.5)
				(thermal_bridge_width 0.5)
				(island_removal_mode 0)
			)
			(polygon
				(pts
					(xy 299.420788 -3.085846) (xy 299.420788 -2.990342) (xy 300.017688 -2.990342) (xy 300.017688 -2.583942)
					(xy 299.420788 -2.583942) (xy 299.420788 -2.49047) (xy 300.017688 -2.49047) (xy 300.017688 -2.08407)
					(xy 299.420788 -2.08407) (xy 299.420788 -1.988566) (xy 300.119288 -1.988566) (xy 300.119288 -3.085846)
				)
			)
		)
	)
	(footprint ""
		(layer "B.Cu")
		(at 163.74618 -117.33022 180)
		(property "Reference" "R407"
			(at 0 0 0)
			(layer "B.SilkS")
			(hide yes)
			(effects
				(font
					(size 1.27 1.27)
				)
				(justify mirror)
			)
		)
		(property "Value" ""
			(at 0 0 0)
			(layer "B.Fab")
			(effects
				(font
					(size 1.27 1.27)
				)
				(justify mirror)
			)
		)
		(duplicate_pad_numbers_are_jumpers no)
		(fp_line
			(start 0.7874 0.4064)
			(end 0.7874 -0.4064)
			(stroke
				(width 0.1524)
				(type default)
			)
			(layer "B.SilkS")
		)
		(fp_line
			(start 0.7874 -0.4064)
			(end -0.7874 -0.4064)
			(stroke
				(width 0.1524)
				(type default)
			)
			(layer "B.SilkS")
		)
		(fp_line
			(start -0.7874 0.4064)
			(end 0.7874 0.4064)
			(stroke
				(width 0.1524)
				(type default)
			)
			(layer "B.SilkS")
		)
		(fp_line
			(start -0.7874 -0.4064)
			(end -0.7874 0.4064)
			(stroke
				(width 0.1524)
				(type default)
			)
			(layer "B.SilkS")
		)
		(fp_line
			(start 0.67945 0.3048)
			(end 0.67945 -0.305054)
			(stroke
				(width 0.1)
				(type default)
			)
			(layer "B.Fab")
		)
		(fp_line
			(start 0.67945 -0.305054)
			(end 0.12065 -0.305054)
			(stroke
				(width 0.1)
				(type default)
			)
			(layer "B.Fab")
		)
		(fp_line
			(start 0.12065 0.3048)
			(end 0.67945 0.3048)
			(stroke
				(width 0.1)
				(type default)
			)
			(layer "B.Fab")
		)
		(fp_line
			(start 0.12065 0.2794)
			(end 0.12065 0.3048)
			(stroke
				(width 0.1)
				(type default)
			)
			(layer "B.Fab")
		)
		(fp_line
			(start 0.12065 -0.2794)
			(end -0.12065 -0.2794)
			(stroke
				(width 0.1)
				(type default)
			)
			(layer "B.Fab")
		)
		(fp_line
			(start 0.12065 -0.305054)
			(end 0.12065 -0.2794)
			(stroke
				(width 0.1)
				(type default)
			)
			(layer "B.Fab")
		)
		(fp_line
			(start -0.120396 0.3048)
			(end -0.120396 0.2794)
			(stroke
				(width 0.1)
				(type default)
			)
			(layer "B.Fab")
		)
		(fp_line
			(start -0.120396 0.2794)
			(end 0.12065 0.2794)
			(stroke
				(width 0.1)
				(type default)
			)
			(layer "B.Fab")
		)
		(fp_line
			(start -0.12065 -0.2794)
			(end -0.12065 -0.3048)
			(stroke
				(width 0.1)
				(type default)
			)
			(layer "B.Fab")
		)
		(fp_line
			(start -0.12065 -0.3048)
			(end -0.67945 -0.3048)
			(stroke
				(width 0.1)
				(type default)
			)
			(layer "B.Fab")
		)
		(fp_line
			(start -0.67945 0.3048)
			(end -0.120396 0.3048)
			(stroke
				(width 0.1)
				(type default)
			)
			(layer "B.Fab")
		)
		(fp_line
			(start -0.67945 -0.3048)
			(end -0.67945 0.3048)
			(stroke
				(width 0.1)
				(type default)
			)
			(layer "B.Fab")
		)
		(pad "1" smd circle
			(at 0.40005 0)
			(size 0 0)
			(layers "B.Cu" "B.Mask" "B.Paste")
			(net "P12V_OCP_V3_2_PLD_PWRGD")
		)
		(pad "2" smd circle
			(at -0.40005 0)
			(size 0 0)
			(layers "B.Cu" "B.Mask" "B.Paste")
			(net "HP_LVC3_OCP_V3_2_P12V_PWRGD_R")
		)
	)
	(footprint ""
		(layer "B.Cu")
		(at 455.084688 -13.102844 90)
		(property "Reference" "R1930"
			(at 0 0 90)
			(layer "B.SilkS")
			(hide yes)
			(effects
				(font
					(size 1.27 1.27)
				)
				(justify mirror)
			)
		)
		(property "Value" ""
			(at 0 0 90)
			(layer "B.Fab")
			(effects
				(font
					(size 1.27 1.27)
				)
				(justify mirror)
			)
		)
		(duplicate_pad_numbers_are_jumpers no)
		(fp_line
			(start 0.7874 -0.4064)
			(end -0.7874 -0.4064)
			(stroke
				(width 0.1524)
				(type default)
			)
			(layer "B.SilkS")
		)
		(fp_line
			(start -0.7874 -0.4064)
			(end -0.7874 0.4064)
			(stroke
				(width 0.1524)
				(type default)
			)
			(layer "B.SilkS")
		)
		(fp_line
			(start 0.7874 0.4064)
			(end 0.7874 -0.4064)
			(stroke
				(width 0.1524)
				(type default)
			)
			(layer "B.SilkS")
		)
		(fp_line
			(start -0.7874 0.4064)
			(end 0.7874 0.4064)
			(stroke
				(width 0.1524)
				(type default)
			)
			(layer "B.SilkS")
		)
		(fp_line
			(start 0.67945 -0.305054)
			(end 0.12065 -0.305054)
			(stroke
				(width 0.1)
				(type default)
			)
			(layer "B.Fab")
		)
		(fp_line
			(start 0.12065 -0.305054)
			(end 0.12065 -0.2794)
			(stroke
				(width 0.1)
				(type default)
			)
			(layer "B.Fab")
		)
		(fp_line
			(start -0.12065 -0.3048)
			(end -0.67945 -0.3048)
			(stroke
				(width 0.1)
				(type default)
			)
			(layer "B.Fab")
		)
		(fp_line
			(start -0.67945 -0.3048)
			(end -0.67945 0.3048)
			(stroke
				(width 0.1)
				(type default)
			)
			(layer "B.Fab")
		)
		(fp_line
			(start 0.12065 -0.2794)
			(end -0.12065 -0.2794)
			(stroke
				(width 0.1)
				(type default)
			)
			(layer "B.Fab")
		)
		(fp_line
			(start -0.12065 -0.2794)
			(end -0.12065 -0.3048)
			(stroke
				(width 0.1)
				(type default)
			)
			(layer "B.Fab")
		)
		(fp_line
			(start 0.12065 0.2794)
			(end 0.12065 0.3048)
			(stroke
				(width 0.1)
				(type default)
			)
			(layer "B.Fab")
		)
		(fp_line
			(start -0.120396 0.2794)
			(end 0.12065 0.2794)
			(stroke
				(width 0.1)
				(type default)
			)
			(layer "B.Fab")
		)
		(fp_line
			(start 0.67945 0.3048)
			(end 0.67945 -0.305054)
			(stroke
				(width 0.1)
				(type default)
			)
			(layer "B.Fab")
		)
		(fp_line
			(start 0.12065 0.3048)
			(end 0.67945 0.3048)
			(stroke
				(width 0.1)
				(type default)
			)
			(layer "B.Fab")
		)
		(fp_line
			(start -0.120396 0.3048)
			(end -0.120396 0.2794)
			(stroke
				(width 0.1)
				(type default)
			)
			(layer "B.Fab")
		)
		(fp_line
			(start -0.67945 0.3048)
			(end -0.120396 0.3048)
			(stroke
				(width 0.1)
				(type default)
			)
			(layer "B.Fab")
		)
		(pad "1" smd circle
			(at 0.40005 0 270)
			(size 0 0)
			(layers "B.Cu" "B.Mask" "B.Paste")
			(net "GND")
		)
		(pad "2" smd circle
			(at -0.40005 0 270)
			(size 0 0)
			(layers "B.Cu" "B.Mask" "B.Paste")
			(net "OCP_SFF_MAIN_PWR_EN")
		)
	)
)
